(kicad_pcb
	(version 20240108)
	(generator "pcbnew")
	(generator_version "8.0")
	(general
		(thickness 1.62)
		(legacy_teardrops no)
	)
	(paper "A4")
	(title_block
		(title "Jetson Orin Baseboard")
		(date "2025-03-12")
		(rev "1.3.4")
		(company "Antmicro Ltd")
		(comment 1 "www.antmicro.com")
		(comment 9 "footprints 273-276 of 677")
	)
	(layers
		(0 "F.Cu" signal)
		(1 "In1.Cu" signal)
		(2 "In2.Cu" signal)
		(3 "In3.Cu" signal)
		(4 "In4.Cu" jumper)
		(5 "In5.Cu" signal)
		(6 "In6.Cu" signal)
		(31 "B.Cu" signal)
		(32 "B.Adhes" user "B.Adhesive")
		(33 "F.Adhes" user "F.Adhesive")
		(34 "B.Paste" user)
		(35 "F.Paste" user)
		(36 "B.SilkS" user "B.Silkscreen")
		(37 "F.SilkS" user "F.Silkscreen")
		(38 "B.Mask" user)
		(39 "F.Mask" user)
		(40 "Dwgs.User" user "User.Drawings")
		(41 "Cmts.User" user "User.Comments")
		(42 "Eco1.User" user "User.Eco1")
		(43 "Eco2.User" user "User.Eco2")
		(44 "Edge.Cuts" user)
		(45 "Margin" user)
		(46 "B.CrtYd" user "B.Courtyard")
		(47 "F.CrtYd" user "F.Courtyard")
		(48 "B.Fab" user)
		(49 "F.Fab" user)
	)
	(footprint "antmicro-footprints:TP_SMD_0.75mm"
		(layer "F.Cu")
		(at 127.905 114.225 180)
		(property "Reference" "TP7"
			(at -0.445 -0.45 180)
			(layer "F.SilkS")
			(effects
				(font
					(size 0.7 0.7)
					(thickness 0.15)
				)
				(justify left bottom)
			)
		)
		(property "Value" "TP_0.75mm_SMD"
			(at 0 1.2 180)
			(layer "F.Fab")
			(effects
				(font
					(size 0.7 0.7)
					(thickness 0.15)
				)
				(justify left bottom)
			)
		)
		(property "Footprint" "antmicro-footprints:TP_SMD_0.75mm"
			(at 0 0 180)
			(layer "F.Fab")
			(hide yes)
			(effects
				(font
					(size 1.27 1.27)
					(thickness 0.15)
				)
			)
		)
		(property "Author" "Antmicro"
			(at 255.81 228.45 0)
			(layer "F.Fab")
			(hide yes)
			(effects
				(font
					(size 1 1)
					(thickness 0.15)
				)
			)
		)
		(property "License" "Apache-2.0"
			(at 255.81 228.45 0)
			(layer "F.Fab")
			(hide yes)
			(effects
				(font
					(size 1 1)
					(thickness 0.15)
				)
			)
		)
		(property "MPN" ""
			(at 255.81 228.45 0)
			(layer "F.Fab")
			(hide yes)
			(effects
				(font
					(size 1 1)
					(thickness 0.15)
				)
			)
		)
		(property "Manufacturer" ""
			(at 255.81 228.45 0)
			(layer "F.Fab")
			(hide yes)
			(effects
				(font
					(size 1 1)
					(thickness 0.15)
				)
			)
		)
		(sheetname "M.2")
		(sheetfile "m-2.kicad_sch")
		(attr exclude_from_pos_files exclude_from_bom)
		(fp_circle
			(center 0 0)
			(end 0.475 0)
			(stroke
				(width 0.05)
				(type default)
			)
			(fill none)
			(layer "F.CrtYd")
		)
		(fp_text user "${REFERENCE}"
			(at -0.4 2.7 180)
			(layer "F.Fab")
			(hide yes)
			(effects
				(font
					(size 0.7 0.7)
					(thickness 0.15)
				)
				(justify left bottom)
			)
		)
		(fp_text user "Author: Antmicro"
			(at -0.4 3.901 180)
			(layer "F.Fab")
			(hide yes)
			(effects
				(font
					(size 0.7 0.7)
					(thickness 0.15)
				)
				(justify left bottom)
			)
		)
		(fp_text user "License: Apache-2.0"
			(at -0.4 5.101 180)
			(layer "F.Fab")
			(hide yes)
			(effects
				(font
					(size 0.7 0.7)
					(thickness 0.15)
				)
				(justify left bottom)
			)
		)
		(pad "1" smd circle
			(at 0 0 180)
			(size 0.75 0.75)
			(layers "F.Cu" "F.Mask")
			(net 220 "/M.2/M2_E_W_DIS_1")
			(pinfunction "1")
			(pintype "passive")
		)
	)
	(footprint "antmicro-footprints:VQFN-HR-10_2x2mm"
		(layer "F.Cu")
		(at 56.73 90.05 180)
		(property "Reference" "U29"
			(at 1.375 -0.725 0)
			(layer "F.SilkS")
			(effects
				(font
					(size 0.7 0.7)
					(thickness 0.15)
				)
				(justify right top)
			)
		)
		(property "Value" "TPS259474"
			(at 0 2.8 0)
			(layer "F.Fab")
			(effects
				(font
					(size 0.7 0.7)
					(thickness 0.15)
				)
				(justify right top)
			)
		)
		(property "Footprint" "antmicro-footprints:VQFN-HR-10_2x2mm"
			(at 0 -0.045 0)
			(layer "F.Fab")
			(hide yes)
			(effects
				(font
					(size 1.27 1.27)
					(thickness 0.15)
				)
			)
		)
		(property "Datasheet" "https://www.ti.com/lit/ds/symlink/tps25947.pdf"
			(at 0 -0.045 0)
			(layer "F.Fab")
			(hide yes)
			(effects
				(font
					(size 1.27 1.27)
					(thickness 0.15)
				)
			)
		)
		(property "Description" "Reverse Current Blocking eFuse with Input Reverse Polarity Protection, 5.5A, 23V, -40 to 125 Deg C, VQFN-HR-10"
			(at -0.05 3.75 0)
			(layer "F.Fab")
			(hide yes)
			(effects
				(font
					(size 0.7 0.7)
					(thickness 0.15)
				)
			)
		)
		(property "MPN" "TPS259474ARPWR"
			(at 0 0 180)
			(unlocked yes)
			(layer "F.Fab")
			(hide yes)
			(effects
				(font
					(size 1 1)
					(thickness 0.15)
				)
			)
		)
		(property "Manufacturer" "Texas Instruments"
			(at 0 0 180)
			(unlocked yes)
			(layer "F.Fab")
			(hide yes)
			(effects
				(font
					(size 1 1)
					(thickness 0.15)
				)
			)
		)
		(property "Author" "Antmicro"
			(at 0 0 180)
			(unlocked yes)
			(layer "F.Fab")
			(hide yes)
			(effects
				(font
					(size 1 1)
					(thickness 0.15)
				)
			)
		)
		(property "License" "Apache-2.0"
			(at 0 0 180)
			(unlocked yes)
			(layer "F.Fab")
			(hide yes)
			(effects
				(font
					(size 1 1)
					(thickness 0.15)
				)
			)
		)
		(sheetname "Supply")
		(sheetfile "supply.kicad_sch")
		(attr smd)
		(fp_circle
			(center -1.2 -1.195)
			(end -1.15 -1.195)
			(stroke
				(width 0.15)
				(type solid)
			)
			(fill solid)
			(layer "F.SilkS")
		)
		(fp_rect
			(start -1.45 -1.45)
			(end 1.45 1.45)
			(stroke
				(width 0.05)
				(type default)
			)
			(fill none)
			(layer "F.CrtYd")
		)
		(fp_line
			(start 1 1)
			(end -1 1)
			(stroke
				(width 0.1)
				(type default)
			)
			(layer "F.Fab")
		)
		(fp_line
			(start 1 -1)
			(end 1 1)
			(stroke
				(width 0.1)
				(type default)
			)
			(layer "F.Fab")
		)
		(fp_line
			(start -0.5 -1)
			(end 1 -1)
			(stroke
				(width 0.1)
				(type default)
			)
			(layer "F.Fab")
		)
		(fp_line
			(start -0.5 -1)
			(end -1 -0.5)
			(stroke
				(width 0.1)
				(type default)
			)
			(layer "F.Fab")
		)
		(fp_line
			(start -1 1)
			(end -1 -0.5)
			(stroke
				(width 0.1)
				(type default)
			)
			(layer "F.Fab")
		)
		(fp_text user "${REFERENCE}"
			(at -2.851 5.45 0)
			(layer "F.Fab")
			(hide yes)
			(effects
				(font
					(size 0.7 0.7)
					(thickness 0.15)
				)
				(justify right top)
			)
		)
		(fp_text user "Author: Antmicro"
			(at -2.851 6.65 0)
			(layer "F.Fab")
			(hide yes)
			(effects
				(font
					(size 0.7 0.7)
					(thickness 0.15)
				)
				(justify right top)
			)
		)
		(fp_text user "License: Apache-2.0"
			(at -2.851 7.85 0)
			(layer "F.Fab")
			(hide yes)
			(effects
				(font
					(size 0.7 0.7)
					(thickness 0.15)
				)
				(justify right top)
			)
		)
		(pad "" smd roundrect
			(at -0.9 -0.6875 180)
			(size 0.6 0.275)
			(layers "F.Paste")
			(roundrect_rratio 0.1818181818)
			(thermal_bridge_angle 45)
		)
		(pad "" smd roundrect
			(at -0.9 0.6875 180)
			(size 0.6 0.275)
			(layers "F.Paste")
			(roundrect_rratio 0.1818181818)
			(thermal_bridge_angle 45)
		)
		(pad "" smd roundrect
			(at -0.7125 -0.875 180)
			(size 0.225 0.65)
			(layers "F.Paste")
			(roundrect_rratio 0.2222222222)
			(thermal_bridge_angle 45)
		)
		(pad "" smd roundrect
			(at -0.7125 0.875 180)
			(size 0.225 0.65)
			(layers "F.Paste")
			(roundrect_rratio 0.2222222222)
			(thermal_bridge_angle 45)
		)
		(pad "" smd roundrect
			(at -0.25 -0.63 180)
			(size 0.28 1.06)
			(layers "F.Paste")
			(roundrect_rratio 0.1785714286)
			(thermal_bridge_angle 45)
		)
		(pad "" smd roundrect
			(at -0.25 0.63 180)
			(size 0.28 1.06)
			(layers "F.Paste")
			(roundrect_rratio 0.1785714286)
			(thermal_bridge_angle 45)
		)
		(pad "" smd roundrect
			(at 0.25 -0.63 180)
			(size 0.28 1.06)
			(layers "F.Paste")
			(roundrect_rratio 0.1785714286)
			(thermal_bridge_angle 45)
		)
		(pad "" smd roundrect
			(at 0.25 0.63 180)
			(size 0.28 1.06)
			(layers "F.Paste")
			(roundrect_rratio 0.1785714286)
			(thermal_bridge_angle 45)
		)
		(pad "" smd roundrect
			(at 0.7125 -0.875 180)
			(size 0.225 0.65)
			(layers "F.Paste")
			(roundrect_rratio 0.2222222222)
			(thermal_bridge_angle 45)
		)
		(pad "" smd roundrect
			(at 0.7125 0.875 180)
			(size 0.225 0.65)
			(layers "F.Paste")
			(roundrect_rratio 0.2222222222)
			(thermal_bridge_angle 45)
		)
		(pad "" smd roundrect
			(at 0.9 -0.6875 180)
			(size 0.6 0.275)
			(layers "F.Paste")
			(roundrect_rratio 0.1818181818)
			(thermal_bridge_angle 45)
		)
		(pad "" smd roundrect
			(at 0.9 0.6875 180)
			(size 0.6 0.275)
			(layers "F.Paste")
			(roundrect_rratio 0.1818181818)
			(thermal_bridge_angle 45)
		)
		(pad "1" smd roundrect
			(at -0.9 -0.7 180)
			(size 0.6 0.3)
			(layers "F.Cu" "F.Mask")
			(roundrect_rratio 0.1666666667)
			(net 787 "+5V_SoM")
			(pinfunction "EN/UVLO")
			(pintype "input")
			(thermal_bridge_angle 45)
		)
		(pad "1" smd roundrect
			(at -0.725 -0.875)
			(size 0.25 0.65)
			(layers "F.Cu" "F.Mask")
			(roundrect_rratio 0.2)
			(net 787 "+5V_SoM")
			(pinfunction "EN/UVLO")
			(pintype "input")
			(thermal_bridge_angle 45)
		)
		(pad "2" smd roundrect
			(at -0.9 -0.225 180)
			(size 0.6 0.25)
			(layers "F.Cu" "F.Paste" "F.Mask")
			(roundrect_rratio 0.2)
			(net 1 "GND")
			(pinfunction "OVLO")
			(pintype "input")
			(thermal_bridge_angle 45)
		)
		(pad "3" smd roundrect
			(at -0.9 0.225 180)
			(size 0.6 0.25)
			(layers "F.Cu" "F.Paste" "F.Mask")
			(roundrect_rratio 0.2)
			(net 792 "Net-(U29-PG)")
			(pinfunction "PG")
			(pintype "output")
			(thermal_bridge_angle 45)
		)
		(pad "4" smd roundrect
			(at -0.9 0.7 180)
			(size 0.6 0.3)
			(layers "F.Cu" "F.Mask")
			(roundrect_rratio 0.1666666667)
			(net 787 "+5V_SoM")
			(pinfunction "PGTH")
			(pintype "input")
			(thermal_bridge_angle 45)
		)
		(pad "4" smd roundrect
			(at -0.725 0.875)
			(size 0.25 0.65)
			(layers "F.Cu" "F.Mask")
			(roundrect_rratio 0.2)
			(net 787 "+5V_SoM")
			(pinfunction "PGTH")
			(pintype "input")
			(thermal_bridge_angle 45)
		)
		(pad "5" smd roundrect
			(at -0.25 0 180)
			(size 0.3 2.4)
			(layers "F.Cu" "F.Mask")
			(roundrect_rratio 0.25)
			(net 787 "+5V_SoM")
			(pinfunction "IN")
			(pintype "power_in")
			(thermal_bridge_angle 45)
		)
		(pad "6" smd roundrect
			(at 0.25 0 180)
			(size 0.3 2.4)
			(layers "F.Cu" "F.Mask")
			(roundrect_rratio 0.25)
			(net 788 "VDD_SoM")
			(pinfunction "OUT")
			(pintype "power_out")
			(thermal_bridge_angle 45)
		)
		(pad "7" smd roundrect
			(at 0.725 0.875)
			(size 0.25 0.65)
			(layers "F.Cu" "F.Mask")
			(roundrect_rratio 0.2)
			(net 751 "Net-(U29-DVDT)")
			(pinfunction "DVDT")
			(pintype "output")
			(thermal_bridge_angle 45)
		)
		(pad "7" smd roundrect
			(at 0.9 0.7)
			(size 0.6 0.3)
			(layers "F.Cu" "F.Mask")
			(roundrect_rratio 0.1666666667)
			(net 751 "Net-(U29-DVDT)")
			(pinfunction "DVDT")
			(pintype "output")
			(thermal_bridge_angle 45)
		)
		(pad "8" smd roundrect
			(at 0.9 0.225)
			(size 0.6 0.25)
			(layers "F.Cu" "F.Paste" "F.Mask")
			(roundrect_rratio 0.2)
			(net 1 "GND")
			(pinfunction "GND")
			(pintype "power_in")
			(thermal_bridge_angle 45)
		)
		(pad "9" smd roundrect
			(at 0.9 -0.225)
			(size 0.6 0.25)
			(layers "F.Cu" "F.Paste" "F.Mask")
			(roundrect_rratio 0.2)
			(net 790 "Net-(U29-ILIM)")
			(pinfunction "ILIM")
			(pintype "output")
			(thermal_bridge_angle 45)
		)
		(pad "10" smd roundrect
			(at 0.725 -0.875)
			(size 0.25 0.65)
			(layers "F.Cu" "F.Mask")
			(roundrect_rratio 0.2)
			(net 794 "unconnected-(U29-ITIMER-Pad10)")
			(pinfunction "ITIMER")
			(pintype "output+no_connect")
			(thermal_bridge_angle 45)
		)
		(pad "10" smd roundrect
			(at 0.9 -0.7)
			(size 0.6 0.3)
			(layers "F.Cu" "F.Mask")
			(roundrect_rratio 0.1666666667)
			(net 795 "unconnected-(U29-ITIMER-Pad10)_1")
			(pinfunction "ITIMER")
			(pintype "output+no_connect")
			(thermal_bridge_angle 45)
		)
	)
	(footprint "antmicro-footprints:R_0402_1005Metric"
		(layer "F.Cu")
		(at 68.67 97.5 90)
		(descr "Resistor SMD 0402")
		(tags "resistor SMD 0402")
		(property "Reference" "R263"
			(at -1.1 1.355 90)
			(layer "F.SilkS")
			(effects
				(font
					(size 0.7 0.7)
					(thickness 0.15)
				)
				(justify left bottom)
			)
		)
		(property "Value" "R_20k_0402"
			(at -1.011843 1.772047 90)
			(layer "F.Fab")
			(effects
				(font
					(size 0.7 0.7)
					(thickness 0.15)
				)
				(justify left bottom)
			)
		)
		(property "Footprint" "antmicro-footprints:R_0402_1005Metric"
			(at 0 0 90)
			(layer "F.Fab")
			(hide yes)
			(effects
				(font
					(size 1.27 1.27)
					(thickness 0.15)
				)
			)
		)
		(property "Datasheet" "https://www.bourns.com/docs/product-datasheets/cr.pdf"
			(at 0 0 90)
			(layer "F.Fab")
			(hide yes)
			(effects
				(font
					(size 1.27 1.27)
					(thickness 0.15)
				)
			)
		)
		(property "Description" "SMD Chip Resistor, 20 kohm, ± 1%, 62.5 mW, 0402 [1005 Metric], Thick Film, General Purpose"
			(at 0 0 90)
			(layer "F.Fab")
			(hide yes)
			(effects
				(font
					(size 1.27 1.27)
					(thickness 0.15)
				)
			)
		)
		(property "Author" "Antmicro"
			(at 166.17 28.83 0)
			(layer "F.Fab")
			(hide yes)
			(effects
				(font
					(size 1 1)
					(thickness 0.15)
				)
			)
		)
		(property "License" "Apache-2.0"
			(at 166.17 28.83 0)
			(layer "F.Fab")
			(hide yes)
			(effects
				(font
					(size 1 1)
					(thickness 0.15)
				)
			)
		)
		(property "MPN" "CR0402-FX-2002GLF"
			(at 166.17 28.83 0)
			(layer "F.Fab")
			(hide yes)
			(effects
				(font
					(size 1 1)
					(thickness 0.15)
				)
			)
		)
		(property "Manufacturer" "Bourns"
			(at 166.17 28.83 0)
			(layer "F.Fab")
			(hide yes)
			(effects
				(font
					(size 1 1)
					(thickness 0.15)
				)
			)
		)
		(property "Tolerance" "1%"
			(at 166.17 28.83 0)
			(layer "F.Fab")
			(hide yes)
			(effects
				(font
					(size 1 1)
					(thickness 0.15)
				)
			)
		)
		(property "Val" "20k"
			(at 166.17 28.83 0)
			(layer "F.Fab")
			(hide yes)
			(effects
				(font
					(size 1 1)
					(thickness 0.15)
				)
			)
		)
		(sheetname "Supply")
		(sheetfile "supply.kicad_sch")
		(attr smd)
		(fp_rect
			(start -0.925 -0.47)
			(end 0.925 0.47)
			(stroke
				(width 0.05)
				(type default)
			)
			(fill none)
			(layer "F.CrtYd")
		)
		(fp_rect
			(start -0.5 -0.25)
			(end 0.5 0.25)
			(stroke
				(width 0.15)
				(type solid)
			)
			(fill none)
			(layer "F.Fab")
		)
		(fp_text user "License: Apache-2.0"
			(at -0.95 5.169 90)
			(layer "F.Fab")
			(hide yes)
			(effects
				(font
					(size 0.7 0.7)
					(thickness 0.15)
				)
				(justify left bottom)
			)
		)
		(fp_text user "Author: Antmicro"
			(at -0.95 4.169 90)
			(layer "F.Fab")
			(hide yes)
			(effects
				(font
					(size 0.7 0.7)
					(thickness 0.15)
				)
				(justify left bottom)
			)
		)
		(fp_text user "${REFERENCE}"
			(at -0.95 3.168 90)
			(layer "F.Fab")
			(hide yes)
			(effects
				(font
					(size 0.7 0.7)
					(thickness 0.15)
				)
				(justify left bottom)
			)
		)
		(pad "1" smd roundrect
			(at -0.48 0 90)
			(size 0.59 0.64)
			(layers "F.Cu" "F.Paste" "F.Mask")
			(roundrect_rratio 0.25)
			(net 712 "/Supply/5V_EN")
			(pintype "passive")
		)
		(pad "2" smd roundrect
			(at 0.48 0 90)
			(size 0.59 0.64)
			(layers "F.Cu" "F.Paste" "F.Mask")
			(roundrect_rratio 0.25)
			(net 115 "VCC")
			(pintype "passive")
		)
	)
	(footprint "antmicro-footprints:R_0402_1005Metric"
		(layer "F.Cu")
		(at 38.2 104.7 180)
		(descr "Resistor SMD 0402")
		(tags "resistor SMD 0402")
		(property "Reference" "R198"
			(at 3.65 -0.4 180)
			(layer "F.SilkS")
			(effects
				(font
					(size 0.7 0.7)
					(thickness 0.15)
				)
				(justify left bottom)
			)
		)
		(property "Value" "R_470k_0402"
			(at 0 1.4 180)
			(layer "F.Fab")
			(effects
				(font
					(size 0.7 0.7)
					(thickness 0.15)
				)
				(justify left bottom)
			)
		)
		(property "Footprint" "antmicro-footprints:R_0402_1005Metric"
			(at 0 0 180)
			(layer "F.Fab")
			(hide yes)
			(effects
				(font
					(size 1.27 1.27)
					(thickness 0.15)
				)
			)
		)
		(property "Datasheet" "https://www.bourns.com/docs/product-datasheets/cr.pdf"
			(at 0 0 180)
			(layer "F.Fab")
			(hide yes)
			(effects
				(font
					(size 1.27 1.27)
					(thickness 0.15)
				)
			)
		)
		(property "Author" "Antmicro"
			(at 76.4 209.4 0)
			(layer "F.Fab")
			(hide yes)
			(effects
				(font
					(size 1 1)
					(thickness 0.15)
				)
			)
		)
		(property "License" "Apache-2.0"
			(at 76.4 209.4 0)
			(layer "F.Fab")
			(hide yes)
			(effects
				(font
					(size 1 1)
					(thickness 0.15)
				)
			)
		)
		(property "MPN" "CR0402-FX-4703GLF"
			(at 76.4 209.4 0)
			(layer "F.Fab")
			(hide yes)
			(effects
				(font
					(size 1 1)
					(thickness 0.15)
				)
			)
		)
		(property "Manufacturer" "Bourns"
			(at 76.4 209.4 0)
			(layer "F.Fab")
			(hide yes)
			(effects
				(font
					(size 1 1)
					(thickness 0.15)
				)
			)
		)
		(property "Tolerance" "1%"
			(at 76.4 209.4 0)
			(layer "F.Fab")
			(hide yes)
			(effects
				(font
					(size 1 1)
					(thickness 0.15)
				)
			)
		)
		(property "Val" "470k"
			(at 76.4 209.4 0)
			(layer "F.Fab")
			(hide yes)
			(effects
				(font
					(size 1 1)
					(thickness 0.15)
				)
			)
		)
		(sheetname "Ethernet")
		(sheetfile "ethernet.kicad_sch")
		(attr smd)
		(fp_rect
			(start -0.925 -0.47)
			(end 0.925 0.47)
			(stroke
				(width 0.05)
				(type default)
			)
			(fill none)
			(layer "F.CrtYd")
		)
		(fp_rect
			(start -0.5 -0.25)
			(end 0.5 0.25)
			(stroke
				(width 0.15)
				(type solid)
			)
			(fill none)
			(layer "F.Fab")
		)
		(fp_text user "License: Apache-2.0"
			(at -0.95 5.169 180)
			(layer "F.Fab")
			(hide yes)
			(effects
				(font
					(size 0.7 0.7)
					(thickness 0.15)
				)
				(justify left bottom)
			)
		)
		(fp_text user "Author: Antmicro"
			(at -0.95 4.169 180)
			(layer "F.Fab")
			(hide yes)
			(effects
				(font
					(size 0.7 0.7)
					(thickness 0.15)
				)
				(justify left bottom)
			)
		)
		(fp_text user "${REFERENCE}"
			(at -0.95 3.168 180)
			(layer "F.Fab")
			(hide yes)
			(effects
				(font
					(size 0.7 0.7)
					(thickness 0.15)
				)
				(justify left bottom)
			)
		)
		(pad "1" smd roundrect
			(at -0.48 0 180)
			(size 0.59 0.64)
			(layers "F.Cu" "F.Paste" "F.Mask")
			(roundrect_rratio 0.25)
			(net 127 "/Ethernet/POE_ACTIVE")
			(pintype "passive")
		)
		(pad "2" smd roundrect
			(at 0.48 0 180)
			(size 0.59 0.64)
			(layers "F.Cu" "F.Paste" "F.Mask")
			(roundrect_rratio 0.25)
			(net 105 "/Ethernet/VDD")
			(pintype "passive")
		)
	)
)
